# S9S_MB_2U (Grand Teton) — schematic netlist excerpt (pin names and nets, part order shuffled) for the footprints in the layout excerpt that follows; sources: Cadence DE-HDL packaged netlist, KiCad conversion of 03242023_DA0F0TMBIJ0_F0T_Motherboard_J_brd_V01_OCP.brd

C3271  Q_CAP  100NF 50V 10% X7R  pkg C0402  page 266 : A = PVNN_TERM_CPU0 ; B = GND
R1226  Q_RES  10K 1% CHIP  pkg 0402LF  page 43 : A = PD_JTAG_CPU0_PLD_TCK ; B = GND

(kicad_pcb
	(version 20260206)
	(generator "pcbnew")
	(generator_version "10.0")
	(general
		(thickness 1.6)
		(legacy_teardrops no)
	)
	(paper "A4")
	(title_block
		(title "03242023_DA0F0TMBIJ0_F0T_Motherboard_J_brd_V01_OCP.brd")
		(comment 1 "Grand Teton / footprints 5957-5958 of 6105")
	)
	(layers
		(0 "F.Cu" signal "TOP")
		(4 "In1.Cu" signal "GND")
		(6 "In2.Cu" signal "IN1")
		(8 "In3.Cu" signal "GND1")
		(10 "In4.Cu" signal "IN2")
		(12 "In5.Cu" signal "GND2")
		(14 "In6.Cu" signal "IN3")
		(16 "In7.Cu" signal "GND3")
		(18 "In8.Cu" signal "VCC")
		(20 "In9.Cu" signal "VCC1")
		(22 "In10.Cu" signal "GND4")
		(24 "In11.Cu" signal "IN4")
		(26 "In12.Cu" signal "GND5")
		(28 "In13.Cu" signal "IN5")
		(30 "In14.Cu" signal "GND6")
		(32 "In15.Cu" signal "IN6")
		(34 "In16.Cu" signal "GND7")
		(2 "B.Cu" signal "BOTTOM")
		(9 "F.Adhes" user "F.Adhesive")
		(11 "B.Adhes" user "B.Adhesive")
		(13 "F.Paste" user "Package Geometry/Pastemask Top")
		(15 "B.Paste" user "Package Geometry/Pastemask Bottom")
		(5 "F.SilkS" user "Ref Des/Silkscreen Top")
		(7 "B.SilkS" user "Ref Des/Silkscreen Bottom")
		(1 "F.Mask" user "Board Geometry/Soldermask Top")
		(3 "B.Mask" user "Board Geometry/Soldermask Bottom")
		(17 "Dwgs.User" user "User.Drawings")
		(19 "Cmts.User" user "User.Comments")
		(21 "Eco1.User" user "User.Eco1")
		(23 "Eco2.User" user "User.Eco2")
		(25 "Edge.Cuts" user "Board Geometry/Outline")
		(27 "Margin" user)
		(31 "F.CrtYd" user "Package Geometry/Place Bound Top")
		(29 "B.CrtYd" user "Package Geometry/Place Bound Bottom")
		(35 "F.Fab" user "Ref Des/Assembly Top")
		(33 "B.Fab" user "Ref Des/Assembly Bottom")
	)
	(footprint ""
		(layer "B.Cu")
		(at 386.58165 -190.82131 90)
		(property "Reference" "R1226"
			(at 0 0 90)
			(layer "B.SilkS")
			(hide yes)
			(effects
				(font
					(size 1.27 1.27)
				)
				(justify mirror)
			)
		)
		(property "Value" ""
			(at 0 0 90)
			(layer "B.Fab")
			(effects
				(font
					(size 1.27 1.27)
				)
				(justify mirror)
			)
		)
		(duplicate_pad_numbers_are_jumpers no)
		(fp_line
			(start 0.7874 -0.4064)
			(end -0.7874 -0.4064)
			(stroke
				(width 0.1524)
				(type default)
			)
			(layer "B.SilkS")
		)
		(fp_line
			(start -0.7874 -0.4064)
			(end -0.7874 0.4064)
			(stroke
				(width 0.1524)
				(type default)
			)
			(layer "B.SilkS")
		)
		(fp_line
			(start 0.7874 0.4064)
			(end 0.7874 -0.4064)
			(stroke
				(width 0.1524)
				(type default)
			)
			(layer "B.SilkS")
		)
		(fp_line
			(start -0.7874 0.4064)
			(end 0.7874 0.4064)
			(stroke
				(width 0.1524)
				(type default)
			)
			(layer "B.SilkS")
		)
		(fp_line
			(start 0.67945 -0.305054)
			(end 0.12065 -0.305054)
			(stroke
				(width 0.1)
				(type default)
			)
			(layer "B.Fab")
		)
		(fp_line
			(start 0.12065 -0.305054)
			(end 0.12065 -0.2794)
			(stroke
				(width 0.1)
				(type default)
			)
			(layer "B.Fab")
		)
		(fp_line
			(start -0.12065 -0.3048)
			(end -0.67945 -0.3048)
			(stroke
				(width 0.1)
				(type default)
			)
			(layer "B.Fab")
		)
		(fp_line
			(start -0.67945 -0.3048)
			(end -0.67945 0.3048)
			(stroke
				(width 0.1)
				(type default)
			)
			(layer "B.Fab")
		)
		(fp_line
			(start 0.12065 -0.2794)
			(end -0.12065 -0.2794)
			(stroke
				(width 0.1)
				(type default)
			)
			(layer "B.Fab")
		)
		(fp_line
			(start -0.12065 -0.2794)
			(end -0.12065 -0.3048)
			(stroke
				(width 0.1)
				(type default)
			)
			(layer "B.Fab")
		)
		(fp_line
			(start 0.12065 0.2794)
			(end 0.12065 0.3048)
			(stroke
				(width 0.1)
				(type default)
			)
			(layer "B.Fab")
		)
		(fp_line
			(start -0.120396 0.2794)
			(end 0.12065 0.2794)
			(stroke
				(width 0.1)
				(type default)
			)
			(layer "B.Fab")
		)
		(fp_line
			(start 0.67945 0.3048)
			(end 0.67945 -0.305054)
			(stroke
				(width 0.1)
				(type default)
			)
			(layer "B.Fab")
		)
		(fp_line
			(start 0.12065 0.3048)
			(end 0.67945 0.3048)
			(stroke
				(width 0.1)
				(type default)
			)
			(layer "B.Fab")
		)
		(fp_line
			(start -0.120396 0.3048)
			(end -0.120396 0.2794)
			(stroke
				(width 0.1)
				(type default)
			)
			(layer "B.Fab")
		)
		(fp_line
			(start -0.67945 0.3048)
			(end -0.120396 0.3048)
			(stroke
				(width 0.1)
				(type default)
			)
			(layer "B.Fab")
		)
		(pad "1" smd circle
			(at 0.40005 0 270)
			(size 0 0)
			(layers "B.Cu" "B.Mask" "B.Paste")
			(net "PD_JTAG_CPU0_PLD_TCK")
		)
		(pad "2" smd circle
			(at -0.40005 0 270)
			(size 0 0)
			(layers "B.Cu" "B.Mask" "B.Paste")
			(net "GND")
		)
	)
	(footprint ""
		(layer "B.Cu")
		(at 348.479364 -356.192836 180)
		(property "Reference" "C3271"
			(at 0 0 0)
			(layer "B.SilkS")
			(hide yes)
			(effects
				(font
					(size 1.27 1.27)
				)
				(justify mirror)
			)
		)
		(property "Value" ""
			(at 0 0 0)
			(layer "B.Fab")
			(effects
				(font
					(size 1.27 1.27)
				)
				(justify mirror)
			)
		)
		(duplicate_pad_numbers_are_jumpers no)
		(fp_line
			(start 0.7874 0.4064)
			(end 0.7874 -0.4064)
			(stroke
				(width 0.1524)
				(type default)
			)
			(layer "B.SilkS")
		)
		(fp_line
			(start 0.7874 -0.4064)
			(end -0.7874 -0.4064)
			(stroke
				(width 0.1524)
				(type default)
			)
			(layer "B.SilkS")
		)
		(fp_line
			(start -0.7874 0.4064)
			(end 0.7874 0.4064)
			(stroke
				(width 0.1524)
				(type default)
			)
			(layer "B.SilkS")
		)
		(fp_line
			(start -0.7874 -0.4064)
			(end -0.7874 0.4064)
			(stroke
				(width 0.1524)
				(type default)
			)
			(layer "B.SilkS")
		)
		(fp_line
			(start 0.67945 0.3048)
			(end 0.67945 -0.305054)
			(stroke
				(width 0.1)
				(type default)
			)
			(layer "B.Fab")
		)
		(fp_line
			(start 0.67945 -0.305054)
			(end 0.12065 -0.305054)
			(stroke
				(width 0.1)
				(type default)
			)
			(layer "B.Fab")
		)
		(fp_line
			(start 0.12065 0.3048)
			(end 0.67945 0.3048)
			(stroke
				(width 0.1)
				(type default)
			)
			(layer "B.Fab")
		)
		(fp_line
			(start 0.12065 0.2794)
			(end 0.12065 0.3048)
			(stroke
				(width 0.1)
				(type default)
			)
			(layer "B.Fab")
		)
		(fp_line
			(start 0.12065 -0.2794)
			(end -0.12065 -0.2794)
			(stroke
				(width 0.1)
				(type default)
			)
			(layer "B.Fab")
		)
		(fp_line
			(start 0.12065 -0.305054)
			(end 0.12065 -0.2794)
			(stroke
				(width 0.1)
				(type default)
			)
			(layer "B.Fab")
		)
		(fp_line
			(start -0.120396 0.3048)
			(end -0.120396 0.2794)
			(stroke
				(width 0.1)
				(type default)
			)
			(layer "B.Fab")
		)
		(fp_line
			(start -0.120396 0.2794)
			(end 0.12065 0.2794)
			(stroke
				(width 0.1)
				(type default)
			)
			(layer "B.Fab")
		)
		(fp_line
			(start -0.12065 -0.2794)
			(end -0.12065 -0.3048)
			(stroke
				(width 0.1)
				(type default)
			)
			(layer "B.Fab")
		)
		(fp_line
			(start -0.12065 -0.3048)
			(end -0.67945 -0.3048)
			(stroke
				(width 0.1)
				(type default)
			)
			(layer "B.Fab")
		)
		(fp_line
			(start -0.67945 0.3048)
			(end -0.120396 0.3048)
			(stroke
				(width 0.1)
				(type default)
			)
			(layer "B.Fab")
		)
		(fp_line
			(start -0.67945 -0.3048)
			(end -0.67945 0.3048)
			(stroke
				(width 0.1)
				(type default)
			)
			(layer "B.Fab")
		)
		(pad "1" smd circle
			(at 0.40005 0)
			(size 0 0)
			(layers "B.Cu" "B.Mask" "B.Paste")
			(net "PVNN_TERM_CPU0")
		)
		(pad "2" smd circle
			(at -0.40005 0)
			(size 0 0)
			(layers "B.Cu" "B.Mask" "B.Paste")
			(net "GND")
		)
	)
)
